(kicad_pcb
	(version 20260206)
	(generator "pcbnew")
	(generator_version "10.0")
	(general
		(thickness 1.6)
		(legacy_teardrops no)
	)
	(paper "A4")
	(title_block
		(title "Wiwynn_Tioga_Pass_MB.brd")
		(comment 1 "Tioga Pass / footprints 57-64 of 4770")
	)
	(layers
		(0 "F.Cu" signal "TOP")
		(4 "In1.Cu" signal "L2GND")
		(6 "In2.Cu" signal "L3")
		(8 "In3.Cu" signal "L4GND")
		(10 "In4.Cu" signal "L5")
		(12 "In5.Cu" signal "L6GND")
		(14 "In6.Cu" signal "L7VCC")
		(16 "In7.Cu" signal "L8VCC")
		(18 "In8.Cu" signal "L9GND")
		(20 "In9.Cu" signal "L10")
		(22 "In10.Cu" signal "L11GND")
		(24 "In11.Cu" signal "L12")
		(26 "In12.Cu" signal "L13GND")
		(2 "B.Cu" signal "BOTTOM")
		(9 "F.Adhes" user "F.Adhesive")
		(11 "B.Adhes" user "B.Adhesive")
		(13 "F.Paste" user "Package Geometry/Pastemask Top")
		(15 "B.Paste" user "Package Geometry/Pastemask Bottom")
		(5 "F.SilkS" user "Ref Des/Silkscreen Top")
		(7 "B.SilkS" user "Ref Des/Silkscreen Bottom")
		(1 "F.Mask" user "Board Geometry/Soldermask Top")
		(3 "B.Mask" user "Board Geometry/Soldermask Bottom")
		(17 "Dwgs.User" user "User.Drawings")
		(19 "Cmts.User" user "User.Comments")
		(21 "Eco1.User" user "User.Eco1")
		(23 "Eco2.User" user "User.Eco2")
		(25 "Edge.Cuts" user "Board Geometry/Outline")
		(27 "Margin" user)
		(31 "F.CrtYd" user "Package Geometry/Place Bound Top")
		(29 "B.CrtYd" user "Package Geometry/Place Bound Bottom")
		(35 "F.Fab" user "Ref Des/Assembly Top")
		(33 "B.Fab" user "Ref Des/Assembly Bottom")
	)
	(footprint ""
		(layer "F.Cu")
		(at 406.273 -128.3335)
		(property "Reference" "C8B1"
			(at 0 0 0)
			(layer "F.SilkS")
			(hide yes)
			(effects
				(font
					(size 1.27 1.27)
				)
			)
		)
		(property "Value" ""
			(at 0 0 0)
			(layer "F.Fab")
			(effects
				(font
					(size 1.27 1.27)
				)
			)
		)
		(duplicate_pad_numbers_are_jumpers no)
		(fp_poly
			(pts
				(xy -0.4953 -0.2032) (xy 0.4953 -0.2032) (xy 0.4953 1.6002) (xy -0.4953 1.6002)
			)
			(stroke
				(width 0)
				(type default)
			)
			(fill no)
			(layer "F.CrtYd")
		)
		(fp_line
			(start -0.4953 -0.2032)
			(end 0.4953 -0.2032)
			(stroke
				(width 0.1)
				(type default)
			)
			(layer "F.Fab")
		)
		(fp_line
			(start -0.4953 1.6002)
			(end -0.4953 -0.2032)
			(stroke
				(width 0.1)
				(type default)
			)
			(layer "F.Fab")
		)
		(fp_line
			(start 0.4953 -0.2032)
			(end 0.4953 1.6002)
			(stroke
				(width 0.1)
				(type default)
			)
			(layer "F.Fab")
		)
		(fp_line
			(start 0.4953 1.6002)
			(end -0.4953 1.6002)
			(stroke
				(width 0.1)
				(type default)
			)
			(layer "F.Fab")
		)
		(pad "1" smd rect
			(at 0 0)
			(size 0.762 0.889)
			(layers "F.Cu" "F.Mask" "F.Paste")
			(net "P1V8_PCH_STBY")
		)
		(pad "2" smd rect
			(at 0 1.397)
			(size 0.762 0.889)
			(layers "F.Cu" "F.Mask" "F.Paste")
			(net "GND")
		)
		(zone
			(layer "F.Cu")
			(hatch none 0.5)
			(connect_pads
				(clearance 0)
			)
			(min_thickness 0.25)
			(keepout
				(tracks not_allowed)
				(vias allowed)
				(pads allowed)
				(copperpour not_allowed)
				(footprints allowed)
			)
			(placement
				(enabled no)
				(sheetname "")
			)
			(fill
				(thermal_gap 0.5)
				(thermal_bridge_width 0.5)
				(island_removal_mode 0)
			)
			(polygon
				(pts
					(xy 405.892 -127.889) (xy 406.654 -127.889) (xy 406.654 -127.381) (xy 405.892 -127.381)
				)
			)
		)
	)
	(footprint ""
		(layer "F.Cu")
		(at 423.506646 -48.968152)
		(property "Reference" "R25W104"
			(at -0.8382 -0.67818 0)
			(unlocked yes)
			(layer "F.SilkS")
			(effects
				(font
					(size 0.4064 0.254)
					(thickness 0.1524)
				)
				(justify left)
			)
		)
		(property "Value" ""
			(at 0 0 0)
			(layer "F.Fab")
			(effects
				(font
					(size 1.27 1.27)
				)
			)
		)
		(duplicate_pad_numbers_are_jumpers no)
		(fp_poly
			(pts
				(xy -0.2794 -0.1016) (xy 0.2794 -0.1016) (xy 0.2794 0.9906) (xy -0.2794 0.9906)
			)
			(stroke
				(width 0)
				(type default)
			)
			(fill no)
			(layer "F.CrtYd")
		)
		(fp_line
			(start -0.2794 -0.1016)
			(end -0.2794 0.9906)
			(stroke
				(width 0.1)
				(type default)
			)
			(layer "F.Fab")
		)
		(fp_line
			(start -0.2794 0.9906)
			(end 0.2794 0.9906)
			(stroke
				(width 0.1)
				(type default)
			)
			(layer "F.Fab")
		)
		(fp_line
			(start 0.2794 -0.1016)
			(end -0.2794 -0.1016)
			(stroke
				(width 0.1)
				(type default)
			)
			(layer "F.Fab")
		)
		(fp_line
			(start 0.2794 0.9906)
			(end 0.2794 -0.1016)
			(stroke
				(width 0.1)
				(type default)
			)
			(layer "F.Fab")
		)
		(pad "1" smd rect
			(at 0 0)
			(size 0.508 0.508)
			(layers "F.Cu" "F.Mask" "F.Paste")
			(net "P3V3_STBY")
		)
		(pad "2" smd rect
			(at 0 0.889)
			(size 0.508 0.508)
			(layers "F.Cu" "F.Mask" "F.Paste")
			(net "BMC_STRAP_BIT27")
		)
		(zone
			(layer "F.Cu")
			(hatch none 0.5)
			(connect_pads
				(clearance 0)
			)
			(min_thickness 0.25)
			(keepout
				(tracks allowed)
				(vias not_allowed)
				(pads allowed)
				(copperpour not_allowed)
				(footprints allowed)
			)
			(placement
				(enabled no)
				(sheetname "")
			)
			(fill
				(thermal_gap 0.5)
				(thermal_bridge_width 0.5)
				(island_removal_mode 0)
			)
			(polygon
				(pts
					(xy 423.252646 -48.714152) (xy 423.760646 -48.714152) (xy 423.760646 -48.333152) (xy 423.252646 -48.333152)
				)
			)
		)
		(zone
			(layer "F.Cu")
			(hatch none 0.5)
			(connect_pads
				(clearance 0)
			)
			(min_thickness 0.25)
			(keepout
				(tracks not_allowed)
				(vias allowed)
				(pads allowed)
				(copperpour not_allowed)
				(footprints allowed)
			)
			(placement
				(enabled no)
				(sheetname "")
			)
			(fill
				(thermal_gap 0.5)
				(thermal_bridge_width 0.5)
				(island_removal_mode 0)
			)
			(polygon
				(pts
					(xy 423.252646 -48.333152) (xy 423.760646 -48.333152) (xy 423.760646 -48.714152) (xy 423.252646 -48.714152)
				)
			)
		)
	)
	(footprint ""
		(layer "F.Cu")
		(at 164.211 -68.1482 90)
		(property "Reference" "R4D54"
			(at 0 0 90)
			(layer "F.SilkS")
			(hide yes)
			(effects
				(font
					(size 1.27 1.27)
				)
			)
		)
		(property "Value" ""
			(at 0 0 90)
			(layer "F.Fab")
			(effects
				(font
					(size 1.27 1.27)
				)
			)
		)
		(duplicate_pad_numbers_are_jumpers no)
		(fp_poly
			(pts
				(xy -0.2794 -0.1016) (xy 0.2794 -0.1016) (xy 0.2794 0.9906) (xy -0.2794 0.9906)
			)
			(stroke
				(width 0)
				(type default)
			)
			(fill no)
			(layer "F.CrtYd")
		)
		(fp_line
			(start 0.2794 -0.1016)
			(end -0.2794 -0.1016)
			(stroke
				(width 0.1)
				(type default)
			)
			(layer "F.Fab")
		)
		(fp_line
			(start -0.2794 -0.1016)
			(end -0.2794 0.9906)
			(stroke
				(width 0.1)
				(type default)
			)
			(layer "F.Fab")
		)
		(fp_line
			(start 0.2794 0.9906)
			(end 0.2794 -0.1016)
			(stroke
				(width 0.1)
				(type default)
			)
			(layer "F.Fab")
		)
		(fp_line
			(start -0.2794 0.9906)
			(end 0.2794 0.9906)
			(stroke
				(width 0.1)
				(type default)
			)
			(layer "F.Fab")
		)
		(pad "1" smd rect
			(at 0 0 90)
			(size 0.508 0.508)
			(layers "F.Cu" "F.Mask" "F.Paste")
			(net "SVID_DIO0_CPU1_R")
		)
		(pad "2" smd rect
			(at 0 0.889 90)
			(size 0.508 0.508)
			(layers "F.Cu" "F.Mask" "F.Paste")
			(net "SVID_VDIO_PVCCIO_CPU1")
		)
		(zone
			(layer "F.Cu")
			(hatch none 0.5)
			(connect_pads
				(clearance 0)
			)
			(min_thickness 0.25)
			(keepout
				(tracks allowed)
				(vias not_allowed)
				(pads allowed)
				(copperpour not_allowed)
				(footprints allowed)
			)
			(placement
				(enabled no)
				(sheetname "")
			)
			(fill
				(thermal_gap 0.5)
				(thermal_bridge_width 0.5)
				(island_removal_mode 0)
			)
			(polygon
				(pts
					(xy 164.465 -67.8942) (xy 164.465 -68.4022) (xy 164.846 -68.4022) (xy 164.846 -67.8942)
				)
			)
		)
		(zone
			(layer "F.Cu")
			(hatch none 0.5)
			(connect_pads
				(clearance 0)
			)
			(min_thickness 0.25)
			(keepout
				(tracks not_allowed)
				(vias allowed)
				(pads allowed)
				(copperpour not_allowed)
				(footprints allowed)
			)
			(placement
				(enabled no)
				(sheetname "")
			)
			(fill
				(thermal_gap 0.5)
				(thermal_bridge_width 0.5)
				(island_removal_mode 0)
			)
			(polygon
				(pts
					(xy 164.846 -67.8942) (xy 164.846 -68.4022) (xy 164.465 -68.4022) (xy 164.465 -67.8942)
				)
			)
		)
	)
	(footprint ""
		(layer "F.Cu")
		(at 192.6463 -82.209132 90)
		(property "Reference" "RT28"
			(at 1.01473 0.656336 0)
			(unlocked yes)
			(layer "F.SilkS")
			(effects
				(font
					(size 0.4064 0.254)
					(thickness 0.1524)
				)
			)
		)
		(property "Value" ""
			(at 0 0 90)
			(layer "F.Fab")
			(effects
				(font
					(size 1.27 1.27)
				)
			)
		)
		(duplicate_pad_numbers_are_jumpers no)
		(fp_poly
			(pts
				(xy -0.4953 -0.2032) (xy 0.4953 -0.2032) (xy 0.4953 1.6002) (xy -0.4953 1.6002)
			)
			(stroke
				(width 0)
				(type default)
			)
			(fill no)
			(layer "F.CrtYd")
		)
		(fp_line
			(start 0.4953 -0.2032)
			(end 0.4953 1.6002)
			(stroke
				(width 0.1)
				(type default)
			)
			(layer "F.Fab")
		)
		(fp_line
			(start -0.4953 -0.2032)
			(end 0.4953 -0.2032)
			(stroke
				(width 0.1)
				(type default)
			)
			(layer "F.Fab")
		)
		(fp_line
			(start 0.4953 1.6002)
			(end -0.4953 1.6002)
			(stroke
				(width 0.1)
				(type default)
			)
			(layer "F.Fab")
		)
		(fp_line
			(start -0.4953 1.6002)
			(end -0.4953 -0.2032)
			(stroke
				(width 0.1)
				(type default)
			)
			(layer "F.Fab")
		)
		(pad "1" smd rect
			(at 0 0 90)
			(size 0.762 0.889)
			(layers "F.Cu" "F.Mask" "F.Paste")
			(net "VR_PVCCIN_CPU0_PH4_BOOT")
		)
		(pad "2" smd rect
			(at 0 1.397 90)
			(size 0.762 0.889)
			(layers "F.Cu" "F.Mask" "F.Paste")
			(net "VR_PVCCIN_CPU0_PH4_BOOT_R")
		)
		(zone
			(layer "F.Cu")
			(hatch none 0.5)
			(connect_pads
				(clearance 0)
			)
			(min_thickness 0.25)
			(keepout
				(tracks allowed)
				(vias not_allowed)
				(pads allowed)
				(copperpour not_allowed)
				(footprints allowed)
			)
			(placement
				(enabled no)
				(sheetname "")
			)
			(fill
				(thermal_gap 0.5)
				(thermal_bridge_width 0.5)
				(island_removal_mode 0)
			)
			(polygon
				(pts
					(xy 193.5988 -82.590132) (xy 193.0908 -82.590132) (xy 193.0908 -81.828132) (xy 193.5988 -81.828132)
				)
			)
		)
		(zone
			(layer "F.Cu")
			(hatch none 0.5)
			(connect_pads
				(clearance 0)
			)
			(min_thickness 0.25)
			(keepout
				(tracks not_allowed)
				(vias allowed)
				(pads allowed)
				(copperpour not_allowed)
				(footprints allowed)
			)
			(placement
				(enabled no)
				(sheetname "")
			)
			(fill
				(thermal_gap 0.5)
				(thermal_bridge_width 0.5)
				(island_removal_mode 0)
			)
			(polygon
				(pts
					(xy 193.5988 -81.828132) (xy 193.5988 -82.590132) (xy 193.0908 -82.590132) (xy 193.0908 -81.828132)
				)
			)
		)
	)
	(footprint ""
		(layer "F.Cu")
		(at 403.606 4.0894 90)
		(property "Reference" "R8G7"
			(at 0 0 90)
			(layer "F.SilkS")
			(hide yes)
			(effects
				(font
					(size 1.27 1.27)
				)
			)
		)
		(property "Value" ""
			(at 0 0 90)
			(layer "F.Fab")
			(effects
				(font
					(size 1.27 1.27)
				)
			)
		)
		(duplicate_pad_numbers_are_jumpers no)
		(fp_poly
			(pts
				(xy -0.2794 -0.1016) (xy 0.2794 -0.1016) (xy 0.2794 0.9906) (xy -0.2794 0.9906)
			)
			(stroke
				(width 0)
				(type default)
			)
			(fill no)
			(layer "F.CrtYd")
		)
		(fp_line
			(start 0.2794 -0.1016)
			(end -0.2794 -0.1016)
			(stroke
				(width 0.1)
				(type default)
			)
			(layer "F.Fab")
		)
		(fp_line
			(start -0.2794 -0.1016)
			(end -0.2794 0.9906)
			(stroke
				(width 0.1)
				(type default)
			)
			(layer "F.Fab")
		)
		(fp_line
			(start 0.2794 0.9906)
			(end 0.2794 -0.1016)
			(stroke
				(width 0.1)
				(type default)
			)
			(layer "F.Fab")
		)
		(fp_line
			(start -0.2794 0.9906)
			(end 0.2794 0.9906)
			(stroke
				(width 0.1)
				(type default)
			)
			(layer "F.Fab")
		)
		(pad "1" smd rect
			(at 0 0 90)
			(size 0.508 0.508)
			(layers "F.Cu" "F.Mask" "F.Paste")
			(net "JTAG_PLD_TDI")
		)
		(pad "2" smd rect
			(at 0 0.889 90)
			(size 0.508 0.508)
			(layers "F.Cu" "F.Mask" "F.Paste")
			(net "JTAG_PLD_TDI_MUX")
		)
		(zone
			(layer "F.Cu")
			(hatch none 0.5)
			(connect_pads
				(clearance 0)
			)
			(min_thickness 0.25)
			(keepout
				(tracks allowed)
				(vias not_allowed)
				(pads allowed)
				(copperpour not_allowed)
				(footprints allowed)
			)
			(placement
				(enabled no)
				(sheetname "")
			)
			(fill
				(thermal_gap 0.5)
				(thermal_bridge_width 0.5)
				(island_removal_mode 0)
			)
			(polygon
				(pts
					(xy 403.86 4.3434) (xy 403.86 3.8354) (xy 404.241 3.8354) (xy 404.241 4.3434)
				)
			)
		)
		(zone
			(layer "F.Cu")
			(hatch none 0.5)
			(connect_pads
				(clearance 0)
			)
			(min_thickness 0.25)
			(keepout
				(tracks not_allowed)
				(vias allowed)
				(pads allowed)
				(copperpour not_allowed)
				(footprints allowed)
			)
			(placement
				(enabled no)
				(sheetname "")
			)
			(fill
				(thermal_gap 0.5)
				(thermal_bridge_width 0.5)
				(island_removal_mode 0)
			)
			(polygon
				(pts
					(xy 404.241 4.3434) (xy 404.241 3.8354) (xy 403.86 3.8354) (xy 403.86 4.3434)
				)
			)
		)
	)
	(footprint ""
		(layer "F.Cu")
		(at 187.833 -75.057 -90)
		(property "Reference" "CF6"
			(at 0 0 270)
			(layer "F.SilkS")
			(hide yes)
			(effects
				(font
					(size 1.27 1.27)
				)
			)
		)
		(property "Value" "*"
			(at 1.1811 -2.8194 270)
			(unlocked yes)
			(layer "F.Fab")
			(hide yes)
			(effects
				(font
					(size 1.27 1.016)
					(thickness 0.1524)
				)
			)
		)
		(property "Device Type" "SC22P50V2JN-4GP_SMD-BCG-SC22P5A"
			(at 1.1811 -4.3434 270)
			(unlocked yes)
			(layer "F.Fab")
			(hide yes)
			(effects
				(font
					(size 1.27 1.016)
					(thickness 0.1524)
				)
			)
		)
		(duplicate_pad_numbers_are_jumpers no)
		(fp_rect
			(start -0.4318 0.9525)
			(end 0.4318 -0.9525)
			(stroke
				(width 0)
				(type default)
			)
			(fill no)
			(layer "F.CrtYd")
		)
		(fp_rect
			(start -0.4318 0.9525)
			(end 0.4318 -0.9525)
			(stroke
				(width 0)
				(type default)
			)
			(fill no)
			(layer "F.Fab")
		)
		(pad "1" smd custom
			(at 0 -0.4445 270)
			(size 0.1524 0.1524)
			(layers "F.Cu" "F.Mask" "F.Paste")
			(net "VR_PVSA_CPU0_BIREF1")
			(options
				(clearance outline)
				(anchor circle)
			)
			(primitives
				(gr_poly
					(pts
						(arc
							(start 0.3048 -0.2032)
							(mid 0.275042 -0.275042)
							(end 0.2032 -0.3048)
						)
						(arc
							(start -0.2032 -0.3048)
							(mid -0.275042 -0.275042)
							(end -0.3048 -0.2032)
						)
						(arc
							(start -0.3048 0.2032)
							(mid -0.275042 0.275042)
							(end -0.2032 0.3048)
						)
						(arc
							(start 0.2032 0.3048)
							(mid 0.275042 0.275042)
							(end 0.3048 0.2032)
						)
					)
					(width 0)
					(fill yes)
				)
			)
		)
		(pad "2" smd custom
			(at 0 0.4445 270)
			(size 0.1524 0.1524)
			(layers "F.Cu" "F.Mask" "F.Paste")
			(net "ISENSE_PVSA_CPU0_IMON")
			(options
				(clearance outline)
				(anchor circle)
			)
			(primitives
				(gr_poly
					(pts
						(arc
							(start 0.3048 -0.2032)
							(mid 0.275042 -0.275042)
							(end 0.2032 -0.3048)
						)
						(arc
							(start -0.2032 -0.3048)
							(mid -0.275042 -0.275042)
							(end -0.3048 -0.2032)
						)
						(arc
							(start -0.3048 0.2032)
							(mid -0.275042 0.275042)
							(end -0.2032 0.3048)
						)
						(arc
							(start 0.2032 0.3048)
							(mid 0.275042 0.275042)
							(end 0.3048 0.2032)
						)
					)
					(width 0)
					(fill yes)
				)
			)
		)
	)
	(footprint ""
		(layer "F.Cu")
		(at 265.675872 -73.318116)
		(property "Reference" "C5D45"
			(at 0 0 0)
			(layer "F.SilkS")
			(hide yes)
			(effects
				(font
					(size 1.27 1.27)
				)
			)
		)
		(property "Value" ""
			(at 0 0 0)
			(layer "F.Fab")
			(effects
				(font
					(size 1.27 1.27)
				)
			)
		)
		(duplicate_pad_numbers_are_jumpers no)
		(fp_poly
			(pts
				(xy -0.4953 -0.2032) (xy 0.4953 -0.2032) (xy 0.4953 1.6002) (xy -0.4953 1.6002)
			)
			(stroke
				(width 0)
				(type default)
			)
			(fill no)
			(layer "F.CrtYd")
		)
		(fp_line
			(start -0.4953 -0.2032)
			(end 0.4953 -0.2032)
			(stroke
				(width 0.1)
				(type default)
			)
			(layer "F.Fab")
		)
		(fp_line
			(start -0.4953 1.6002)
			(end -0.4953 -0.2032)
			(stroke
				(width 0.1)
				(type default)
			)
			(layer "F.Fab")
		)
		(fp_line
			(start 0.4953 -0.2032)
			(end 0.4953 1.6002)
			(stroke
				(width 0.1)
				(type default)
			)
			(layer "F.Fab")
		)
		(fp_line
			(start 0.4953 1.6002)
			(end -0.4953 1.6002)
			(stroke
				(width 0.1)
				(type default)
			)
			(layer "F.Fab")
		)
		(pad "1" smd rect
			(at 0 0)
			(size 0.762 0.889)
			(layers "F.Cu" "F.Mask" "F.Paste")
			(net "PVCCIN_CPU0")
		)
		(pad "2" smd rect
			(at 0 1.397)
			(size 0.762 0.889)
			(layers "F.Cu" "F.Mask" "F.Paste")
			(net "GND")
		)
		(zone
			(layer "F.Cu")
			(hatch none 0.5)
			(connect_pads
				(clearance 0)
			)
			(min_thickness 0.25)
			(keepout
				(tracks not_allowed)
				(vias allowed)
				(pads allowed)
				(copperpour not_allowed)
				(footprints allowed)
			)
			(placement
				(enabled no)
				(sheetname "")
			)
			(fill
				(thermal_gap 0.5)
				(thermal_bridge_width 0.5)
				(island_removal_mode 0)
			)
			(polygon
				(pts
					(xy 265.294872 -72.873616) (xy 266.056872 -72.873616) (xy 266.056872 -72.365616) (xy 265.294872 -72.365616)
				)
			)
		)
	)
	(footprint ""
		(layer "F.Cu")
		(at 19.220434 -2.643378 -90)
		(property "Reference" "C1G20"
			(at 0 0 270)
			(layer "F.SilkS")
			(hide yes)
			(effects
				(font
					(size 1.27 1.27)
				)
			)
		)
		(property "Value" ""
			(at 0 0 270)
			(layer "F.Fab")
			(effects
				(font
					(size 1.27 1.27)
				)
			)
		)
		(duplicate_pad_numbers_are_jumpers no)
		(fp_rect
			(start -0.7239 -0.2159)
			(end 0.7239 1.9939)
			(stroke
				(width 0)
				(type default)
			)
			(fill no)
			(layer "F.CrtYd")
		)
		(fp_line
			(start -0.7239 1.9939)
			(end 0.7239 1.9939)
			(stroke
				(width 0.1)
				(type default)
			)
			(layer "F.Fab")
		)
		(fp_line
			(start 0.7239 1.9939)
			(end 0.7239 -0.2159)
			(stroke
				(width 0.1)
				(type default)
			)
			(layer "F.Fab")
		)
		(fp_line
			(start -0.7239 -0.2159)
			(end -0.7239 1.9939)
			(stroke
				(width 0.1)
				(type default)
			)
			(layer "F.Fab")
		)
		(fp_line
			(start 0.7239 -0.2159)
			(end -0.7239 -0.2159)
			(stroke
				(width 0.1)
				(type default)
			)
			(layer "F.Fab")
		)
		(pad "1" smd rect
			(at 0 0 270)
			(size 1.27 1.016)
			(layers "F.Cu" "F.Mask" "F.Paste")
			(net "PVDDQ_GHJ")
		)
		(pad "2" smd rect
			(at 0 1.778 270)
			(size 1.27 1.016)
			(layers "F.Cu" "F.Mask" "F.Paste")
			(net "GND")
		)
		(zone
			(layer "F.Cu")
			(hatch none 0.5)
			(connect_pads
				(clearance 0)
			)
			(min_thickness 0.25)
			(keepout
				(tracks not_allowed)
				(vias allowed)
				(pads allowed)
				(copperpour not_allowed)
				(footprints allowed)
			)
			(placement
				(enabled no)
				(sheetname "")
			)
			(fill
				(thermal_gap 0.5)
				(thermal_bridge_width 0.5)
				(island_removal_mode 0)
			)
			(polygon
				(pts
					(xy 18.712434 -3.278378) (xy 17.950434 -3.278378) (xy 17.950434 -2.008378) (xy 18.712434 -2.008378)
				)
			)
		)
	)
)
